(kicad_pcb
	(version 20260206)
	(generator "pcbnew")
	(generator_version "10.0")
	(general
		(thickness 1.6)
		(legacy_teardrops no)
	)
	(paper "A4")
	(title_block
		(title "04192023_DAF0TMB3IC0_F0TG_MB_C_brd_V02_OCP.brd")
		(comment 1 "Grand Teton / footprints 2836-2844 of 8354")
	)
	(layers
		(0 "F.Cu" signal "TOP")
		(4 "In1.Cu" signal "GND")
		(6 "In2.Cu" signal "IN1")
		(8 "In3.Cu" signal "GND1")
		(10 "In4.Cu" signal "IN2")
		(12 "In5.Cu" signal "GND2")
		(14 "In6.Cu" signal "IN3")
		(16 "In7.Cu" signal "GND3")
		(18 "In8.Cu" signal "VCC")
		(20 "In9.Cu" signal "VCC1")
		(22 "In10.Cu" signal "GND4")
		(24 "In11.Cu" signal "IN4")
		(26 "In12.Cu" signal "GND5")
		(28 "In13.Cu" signal "IN5")
		(30 "In14.Cu" signal "GND6")
		(32 "In15.Cu" signal "IN6")
		(34 "In16.Cu" signal "GND7")
		(2 "B.Cu" signal "BOTTOM")
		(9 "F.Adhes" user "F.Adhesive")
		(11 "B.Adhes" user "B.Adhesive")
		(13 "F.Paste" user "Package Geometry/Pastemask Top")
		(15 "B.Paste" user "Package Geometry/Pastemask Bottom")
		(5 "F.SilkS" user "Ref Des/Silkscreen Top")
		(7 "B.SilkS" user "Ref Des/Silkscreen Bottom")
		(1 "F.Mask" user "Board Geometry/Soldermask Top")
		(3 "B.Mask" user "Board Geometry/Soldermask Bottom")
		(17 "Dwgs.User" user "User.Drawings")
		(19 "Cmts.User" user "User.Comments")
		(21 "Eco1.User" user "User.Eco1")
		(23 "Eco2.User" user "User.Eco2")
		(25 "Edge.Cuts" user "Board Geometry/Outline")
		(27 "Margin" user)
		(31 "F.CrtYd" user "Package Geometry/Place Bound Top")
		(29 "B.CrtYd" user "Package Geometry/Place Bound Bottom")
		(35 "F.Fab" user "Ref Des/Assembly Top")
		(33 "B.Fab" user "Ref Des/Assembly Bottom")
	)
	(footprint ""
		(layer "F.Cu")
		(at 384.113278 -139.186158 180)
		(property "Reference" "PR314"
			(at 0 0 180)
			(layer "F.SilkS")
			(hide yes)
			(effects
				(font
					(size 1.27 1.27)
				)
			)
		)
		(property "Value" ""
			(at 0 0 180)
			(layer "F.Fab")
			(effects
				(font
					(size 1.27 1.27)
				)
			)
		)
		(duplicate_pad_numbers_are_jumpers no)
		(fp_line
			(start 0.7874 0.4064)
			(end -0.7874 0.4064)
			(stroke
				(width 0.1524)
				(type default)
			)
			(layer "F.SilkS")
		)
		(fp_line
			(start 0.7874 -0.4064)
			(end 0.7874 0.4064)
			(stroke
				(width 0.1524)
				(type default)
			)
			(layer "F.SilkS")
		)
		(fp_line
			(start -0.7874 0.4064)
			(end -0.7874 -0.4064)
			(stroke
				(width 0.1524)
				(type default)
			)
			(layer "F.SilkS")
		)
		(fp_line
			(start -0.7874 -0.4064)
			(end 0.7874 -0.4064)
			(stroke
				(width 0.1524)
				(type default)
			)
			(layer "F.SilkS")
		)
		(fp_line
			(start 0.67945 0.3048)
			(end 0.120396 0.3048)
			(stroke
				(width 0.1)
				(type default)
			)
			(layer "F.Fab")
		)
		(fp_line
			(start 0.67945 -0.3048)
			(end 0.67945 0.3048)
			(stroke
				(width 0.1)
				(type default)
			)
			(layer "F.Fab")
		)
		(fp_line
			(start 0.12065 -0.2794)
			(end 0.12065 -0.3048)
			(stroke
				(width 0.1)
				(type default)
			)
			(layer "F.Fab")
		)
		(fp_line
			(start 0.12065 -0.3048)
			(end 0.67945 -0.3048)
			(stroke
				(width 0.1)
				(type default)
			)
			(layer "F.Fab")
		)
		(fp_line
			(start 0.120396 0.3048)
			(end 0.120396 0.2794)
			(stroke
				(width 0.1)
				(type default)
			)
			(layer "F.Fab")
		)
		(fp_line
			(start 0.120396 0.2794)
			(end -0.12065 0.2794)
			(stroke
				(width 0.1)
				(type default)
			)
			(layer "F.Fab")
		)
		(fp_line
			(start -0.12065 0.3048)
			(end -0.67945 0.3048)
			(stroke
				(width 0.1)
				(type default)
			)
			(layer "F.Fab")
		)
		(fp_line
			(start -0.12065 0.2794)
			(end -0.12065 0.3048)
			(stroke
				(width 0.1)
				(type default)
			)
			(layer "F.Fab")
		)
		(fp_line
			(start -0.12065 -0.2794)
			(end 0.12065 -0.2794)
			(stroke
				(width 0.1)
				(type default)
			)
			(layer "F.Fab")
		)
		(fp_line
			(start -0.12065 -0.305054)
			(end -0.12065 -0.2794)
			(stroke
				(width 0.1)
				(type default)
			)
			(layer "F.Fab")
		)
		(fp_line
			(start -0.67945 0.3048)
			(end -0.67945 -0.305054)
			(stroke
				(width 0.1)
				(type default)
			)
			(layer "F.Fab")
		)
		(fp_line
			(start -0.67945 -0.305054)
			(end -0.12065 -0.305054)
			(stroke
				(width 0.1)
				(type default)
			)
			(layer "F.Fab")
		)
		(pad "1" smd circle
			(at -0.40005 0 180)
			(size 0 0)
			(layers "F.Cu" "F.Mask" "F.Paste")
			(net "P12V_AUX")
		)
		(pad "2" smd circle
			(at 0.40005 0 180)
			(size 0 0)
			(layers "F.Cu" "F.Mask" "F.Paste")
			(net "PVDDCR_CPU0_P0_VINSEN")
		)
	)
	(footprint ""
		(layer "F.Cu")
		(at 75.05573 -386.951474)
		(property "Reference" "R598"
			(at 0 0 0)
			(layer "F.SilkS")
			(hide yes)
			(effects
				(font
					(size 1.27 1.27)
				)
			)
		)
		(property "Value" ""
			(at 0 0 0)
			(layer "F.Fab")
			(effects
				(font
					(size 1.27 1.27)
				)
			)
		)
		(duplicate_pad_numbers_are_jumpers no)
		(fp_line
			(start -0.32512 -0.175006)
			(end 0.32512 -0.175006)
			(stroke
				(width 0.1)
				(type default)
			)
			(layer "F.Fab")
		)
		(fp_line
			(start -0.32512 0.175006)
			(end -0.32512 -0.175006)
			(stroke
				(width 0.1)
				(type default)
			)
			(layer "F.Fab")
		)
		(fp_line
			(start 0.32512 -0.175006)
			(end 0.32512 0.175006)
			(stroke
				(width 0.1)
				(type default)
			)
			(layer "F.Fab")
		)
		(fp_line
			(start 0.32512 0.175006)
			(end -0.32512 0.175006)
			(stroke
				(width 0.1)
				(type default)
			)
			(layer "F.Fab")
		)
		(pad "1" smd rect
			(at -0.2667 0)
			(size 0.3048 0.381)
			(layers "F.Cu" "F.Mask" "F.Paste")
			(net "CLK_100M_RETIMER_CPU1_P1_R_DN")
		)
		(pad "2" smd rect
			(at 0.2667 0 180)
			(size 0.3048 0.381)
			(layers "F.Cu" "F.Mask" "F.Paste")
			(net "CLK_100M_RETIMER_CPU1_P1_DN")
		)
	)
	(footprint ""
		(layer "F.Cu")
		(at 30.484064 -75.234038 90)
		(property "Reference" "R1318"
			(at 0 0 90)
			(layer "F.SilkS")
			(hide yes)
			(effects
				(font
					(size 1.27 1.27)
				)
			)
		)
		(property "Value" ""
			(at 0 0 90)
			(layer "F.Fab")
			(effects
				(font
					(size 1.27 1.27)
				)
			)
		)
		(duplicate_pad_numbers_are_jumpers no)
		(fp_line
			(start 0.7874 -0.4064)
			(end 0.7874 0.4064)
			(stroke
				(width 0.1524)
				(type default)
			)
			(layer "F.SilkS")
		)
		(fp_line
			(start -0.7874 -0.4064)
			(end 0.7874 -0.4064)
			(stroke
				(width 0.1524)
				(type default)
			)
			(layer "F.SilkS")
		)
		(fp_line
			(start 0.7874 0.4064)
			(end -0.7874 0.4064)
			(stroke
				(width 0.1524)
				(type default)
			)
			(layer "F.SilkS")
		)
		(fp_line
			(start -0.7874 0.4064)
			(end -0.7874 -0.4064)
			(stroke
				(width 0.1524)
				(type default)
			)
			(layer "F.SilkS")
		)
		(fp_line
			(start -0.12065 -0.305054)
			(end -0.12065 -0.2794)
			(stroke
				(width 0.1)
				(type default)
			)
			(layer "F.Fab")
		)
		(fp_line
			(start -0.67945 -0.305054)
			(end -0.12065 -0.305054)
			(stroke
				(width 0.1)
				(type default)
			)
			(layer "F.Fab")
		)
		(fp_line
			(start 0.67945 -0.3048)
			(end 0.67945 0.3048)
			(stroke
				(width 0.1)
				(type default)
			)
			(layer "F.Fab")
		)
		(fp_line
			(start 0.12065 -0.3048)
			(end 0.67945 -0.3048)
			(stroke
				(width 0.1)
				(type default)
			)
			(layer "F.Fab")
		)
		(fp_line
			(start 0.12065 -0.2794)
			(end 0.12065 -0.3048)
			(stroke
				(width 0.1)
				(type default)
			)
			(layer "F.Fab")
		)
		(fp_line
			(start -0.12065 -0.2794)
			(end 0.12065 -0.2794)
			(stroke
				(width 0.1)
				(type default)
			)
			(layer "F.Fab")
		)
		(fp_line
			(start 0.120396 0.2794)
			(end -0.12065 0.2794)
			(stroke
				(width 0.1)
				(type default)
			)
			(layer "F.Fab")
		)
		(fp_line
			(start -0.12065 0.2794)
			(end -0.12065 0.3048)
			(stroke
				(width 0.1)
				(type default)
			)
			(layer "F.Fab")
		)
		(fp_line
			(start 0.67945 0.3048)
			(end 0.120396 0.3048)
			(stroke
				(width 0.1)
				(type default)
			)
			(layer "F.Fab")
		)
		(fp_line
			(start 0.120396 0.3048)
			(end 0.120396 0.2794)
			(stroke
				(width 0.1)
				(type default)
			)
			(layer "F.Fab")
		)
		(fp_line
			(start -0.12065 0.3048)
			(end -0.67945 0.3048)
			(stroke
				(width 0.1)
				(type default)
			)
			(layer "F.Fab")
		)
		(fp_line
			(start -0.67945 0.3048)
			(end -0.67945 -0.305054)
			(stroke
				(width 0.1)
				(type default)
			)
			(layer "F.Fab")
		)
		(pad "1" smd circle
			(at -0.40005 0 90)
			(size 0 0)
			(layers "F.Cu" "F.Mask" "F.Paste")
			(net "PD_U212_EN_N")
		)
		(pad "2" smd circle
			(at 0.40005 0 90)
			(size 0 0)
			(layers "F.Cu" "F.Mask" "F.Paste")
			(net "GND")
		)
	)
	(footprint ""
		(layer "F.Cu")
		(at 47.608744 -421.326564)
		(property "Reference" "R1381"
			(at 0 0 0)
			(layer "F.SilkS")
			(hide yes)
			(effects
				(font
					(size 1.27 1.27)
				)
			)
		)
		(property "Value" ""
			(at 0 0 0)
			(layer "F.Fab")
			(effects
				(font
					(size 1.27 1.27)
				)
			)
		)
		(duplicate_pad_numbers_are_jumpers no)
		(fp_line
			(start -0.32512 -0.175006)
			(end 0.32512 -0.175006)
			(stroke
				(width 0.1)
				(type default)
			)
			(layer "F.Fab")
		)
		(fp_line
			(start -0.32512 0.175006)
			(end -0.32512 -0.175006)
			(stroke
				(width 0.1)
				(type default)
			)
			(layer "F.Fab")
		)
		(fp_line
			(start 0.32512 -0.175006)
			(end 0.32512 0.175006)
			(stroke
				(width 0.1)
				(type default)
			)
			(layer "F.Fab")
		)
		(fp_line
			(start 0.32512 0.175006)
			(end -0.32512 0.175006)
			(stroke
				(width 0.1)
				(type default)
			)
			(layer "F.Fab")
		)
		(pad "1" smd rect
			(at -0.2667 0)
			(size 0.3048 0.381)
			(layers "F.Cu" "F.Mask" "F.Paste")
			(net "JTAG_TCK_RT_CPU1_P0")
		)
		(pad "2" smd rect
			(at 0.2667 0 180)
			(size 0.3048 0.381)
			(layers "F.Cu" "F.Mask" "F.Paste")
			(net "GND")
		)
	)
	(footprint ""
		(layer "F.Cu")
		(at 116.896896 -373.03583 -90)
		(property "Reference" "C1537"
			(at 0 0 270)
			(layer "F.SilkS")
			(hide yes)
			(effects
				(font
					(size 1.27 1.27)
				)
			)
		)
		(property "Value" ""
			(at 0 0 270)
			(layer "F.Fab")
			(effects
				(font
					(size 1.27 1.27)
				)
			)
		)
		(duplicate_pad_numbers_are_jumpers no)
		(fp_line
			(start -0.299974 0.150114)
			(end -0.299974 -0.150114)
			(stroke
				(width 0.1)
				(type default)
			)
			(layer "F.Fab")
		)
		(fp_line
			(start 0.299974 0.150114)
			(end -0.299974 0.150114)
			(stroke
				(width 0.1)
				(type default)
			)
			(layer "F.Fab")
		)
		(fp_line
			(start -0.299974 -0.150114)
			(end 0.299974 -0.150114)
			(stroke
				(width 0.1)
				(type default)
			)
			(layer "F.Fab")
		)
		(fp_line
			(start 0.299974 -0.150114)
			(end 0.299974 0.150114)
			(stroke
				(width 0.1)
				(type default)
			)
			(layer "F.Fab")
		)
		(pad "1" smd rect
			(at -0.2667 0 270)
			(size 0.3048 0.381)
			(layers "F.Cu" "F.Mask" "F.Paste")
			(net "P5E_CPU1_P3_TX_C_DP<5>")
		)
		(pad "2" smd rect
			(at 0.2667 0 270)
			(size 0.3048 0.381)
			(layers "F.Cu" "F.Mask" "F.Paste")
			(net "P5E_CPU1_P3_TX_DP<5>")
		)
	)
	(footprint ""
		(layer "F.Cu")
		(at 306.711096 -381.41783 -90)
		(property "Reference" "C922"
			(at 0 0 270)
			(layer "F.SilkS")
			(hide yes)
			(effects
				(font
					(size 1.27 1.27)
				)
			)
		)
		(property "Value" ""
			(at 0 0 270)
			(layer "F.Fab")
			(effects
				(font
					(size 1.27 1.27)
				)
			)
		)
		(duplicate_pad_numbers_are_jumpers no)
		(fp_line
			(start -0.299974 0.150114)
			(end -0.299974 -0.150114)
			(stroke
				(width 0.1)
				(type default)
			)
			(layer "F.Fab")
		)
		(fp_line
			(start 0.299974 0.150114)
			(end -0.299974 0.150114)
			(stroke
				(width 0.1)
				(type default)
			)
			(layer "F.Fab")
		)
		(fp_line
			(start -0.299974 -0.150114)
			(end 0.299974 -0.150114)
			(stroke
				(width 0.1)
				(type default)
			)
			(layer "F.Fab")
		)
		(fp_line
			(start 0.299974 -0.150114)
			(end 0.299974 0.150114)
			(stroke
				(width 0.1)
				(type default)
			)
			(layer "F.Fab")
		)
		(pad "1" smd rect
			(at -0.2667 0 270)
			(size 0.3048 0.381)
			(layers "F.Cu" "F.Mask" "F.Paste")
			(net "P5E_CPU0_P0_TX_C_DN<5>")
		)
		(pad "2" smd rect
			(at 0.2667 0 270)
			(size 0.3048 0.381)
			(layers "F.Cu" "F.Mask" "F.Paste")
			(net "P5E_CPU0_P0_TX_DN<5>")
		)
	)
	(footprint ""
		(layer "F.Cu")
		(at 33.186878 -16.099536 90)
		(property "Reference" "C691"
			(at 0 0 90)
			(layer "F.SilkS")
			(hide yes)
			(effects
				(font
					(size 1.27 1.27)
				)
			)
		)
		(property "Value" ""
			(at 0 0 90)
			(layer "F.Fab")
			(effects
				(font
					(size 1.27 1.27)
				)
			)
		)
		(duplicate_pad_numbers_are_jumpers no)
		(fp_line
			(start 0.299974 -0.150114)
			(end 0.299974 0.150114)
			(stroke
				(width 0.1)
				(type default)
			)
			(layer "F.Fab")
		)
		(fp_line
			(start -0.299974 -0.150114)
			(end 0.299974 -0.150114)
			(stroke
				(width 0.1)
				(type default)
			)
			(layer "F.Fab")
		)
		(fp_line
			(start 0.299974 0.150114)
			(end -0.299974 0.150114)
			(stroke
				(width 0.1)
				(type default)
			)
			(layer "F.Fab")
		)
		(fp_line
			(start -0.299974 0.150114)
			(end -0.299974 -0.150114)
			(stroke
				(width 0.1)
				(type default)
			)
			(layer "F.Fab")
		)
		(pad "1" smd rect
			(at -0.2667 0 90)
			(size 0.3048 0.381)
			(layers "F.Cu" "F.Mask" "F.Paste")
			(net "P5E_CPU1_G1_TX_C_DP<9>")
		)
		(pad "2" smd rect
			(at 0.2667 0 90)
			(size 0.3048 0.381)
			(layers "F.Cu" "F.Mask" "F.Paste")
			(net "P5E_CPU1_G1_TX_DP<9>")
		)
	)
	(footprint ""
		(layer "F.Cu")
		(at 393.284456 -72.28205)
		(property "Reference" "R1276"
			(at 0 0 0)
			(layer "F.SilkS")
			(hide yes)
			(effects
				(font
					(size 1.27 1.27)
				)
			)
		)
		(property "Value" ""
			(at 0 0 0)
			(layer "F.Fab")
			(effects
				(font
					(size 1.27 1.27)
				)
			)
		)
		(duplicate_pad_numbers_are_jumpers no)
		(fp_line
			(start -0.7874 -0.4064)
			(end 0.7874 -0.4064)
			(stroke
				(width 0.1524)
				(type default)
			)
			(layer "F.SilkS")
		)
		(fp_line
			(start -0.7874 0.4064)
			(end -0.7874 -0.4064)
			(stroke
				(width 0.1524)
				(type default)
			)
			(layer "F.SilkS")
		)
		(fp_line
			(start 0.7874 -0.4064)
			(end 0.7874 0.4064)
			(stroke
				(width 0.1524)
				(type default)
			)
			(layer "F.SilkS")
		)
		(fp_line
			(start 0.7874 0.4064)
			(end -0.7874 0.4064)
			(stroke
				(width 0.1524)
				(type default)
			)
			(layer "F.SilkS")
		)
		(fp_line
			(start -0.67945 -0.305054)
			(end -0.12065 -0.305054)
			(stroke
				(width 0.1)
				(type default)
			)
			(layer "F.Fab")
		)
		(fp_line
			(start -0.67945 0.3048)
			(end -0.67945 -0.305054)
			(stroke
				(width 0.1)
				(type default)
			)
			(layer "F.Fab")
		)
		(fp_line
			(start -0.12065 -0.305054)
			(end -0.12065 -0.2794)
			(stroke
				(width 0.1)
				(type default)
			)
			(layer "F.Fab")
		)
		(fp_line
			(start -0.12065 -0.2794)
			(end 0.12065 -0.2794)
			(stroke
				(width 0.1)
				(type default)
			)
			(layer "F.Fab")
		)
		(fp_line
			(start -0.12065 0.2794)
			(end -0.12065 0.3048)
			(stroke
				(width 0.1)
				(type default)
			)
			(layer "F.Fab")
		)
		(fp_line
			(start -0.12065 0.3048)
			(end -0.67945 0.3048)
			(stroke
				(width 0.1)
				(type default)
			)
			(layer "F.Fab")
		)
		(fp_line
			(start 0.120396 0.2794)
			(end -0.12065 0.2794)
			(stroke
				(width 0.1)
				(type default)
			)
			(layer "F.Fab")
		)
		(fp_line
			(start 0.120396 0.3048)
			(end 0.120396 0.2794)
			(stroke
				(width 0.1)
				(type default)
			)
			(layer "F.Fab")
		)
		(fp_line
			(start 0.12065 -0.3048)
			(end 0.67945 -0.3048)
			(stroke
				(width 0.1)
				(type default)
			)
			(layer "F.Fab")
		)
		(fp_line
			(start 0.12065 -0.2794)
			(end 0.12065 -0.3048)
			(stroke
				(width 0.1)
				(type default)
			)
			(layer "F.Fab")
		)
		(fp_line
			(start 0.67945 -0.3048)
			(end 0.67945 0.3048)
			(stroke
				(width 0.1)
				(type default)
			)
			(layer "F.Fab")
		)
		(fp_line
			(start 0.67945 0.3048)
			(end 0.120396 0.3048)
			(stroke
				(width 0.1)
				(type default)
			)
			(layer "F.Fab")
		)
		(pad "1" smd circle
			(at -0.40005 0)
			(size 0 0)
			(layers "F.Cu" "F.Mask" "F.Paste")
			(net "SMB_INA230_6_3V3AUX_SDA_R")
		)
		(pad "2" smd circle
			(at 0.40005 0)
			(size 0 0)
			(layers "F.Cu" "F.Mask" "F.Paste")
			(net "SMB_INA230_6_3V3AUX_SDA_R1")
		)
	)
	(footprint ""
		(layer "F.Cu")
		(at 268.59992 -124.469398)
		(property "Reference" "C2056"
			(at 0 0 0)
			(layer "F.SilkS")
			(hide yes)
			(effects
				(font
					(size 1.27 1.27)
				)
			)
		)
		(property "Value" ""
			(at 0 0 0)
			(layer "F.Fab")
			(effects
				(font
					(size 1.27 1.27)
				)
			)
		)
		(duplicate_pad_numbers_are_jumpers no)
		(fp_line
			(start -0.7874 -0.4064)
			(end 0.7874 -0.4064)
			(stroke
				(width 0.1524)
				(type default)
			)
			(layer "F.SilkS")
		)
		(fp_line
			(start -0.7874 0.4064)
			(end -0.7874 -0.4064)
			(stroke
				(width 0.1524)
				(type default)
			)
			(layer "F.SilkS")
		)
		(fp_line
			(start 0.7874 -0.4064)
			(end 0.7874 0.4064)
			(stroke
				(width 0.1524)
				(type default)
			)
			(layer "F.SilkS")
		)
		(fp_line
			(start 0.7874 0.4064)
			(end -0.7874 0.4064)
			(stroke
				(width 0.1524)
				(type default)
			)
			(layer "F.SilkS")
		)
		(fp_line
			(start -0.67945 -0.305054)
			(end -0.12065 -0.305054)
			(stroke
				(width 0.1)
				(type default)
			)
			(layer "F.Fab")
		)
		(fp_line
			(start -0.67945 0.3048)
			(end -0.67945 -0.305054)
			(stroke
				(width 0.1)
				(type default)
			)
			(layer "F.Fab")
		)
		(fp_line
			(start -0.12065 -0.305054)
			(end -0.12065 -0.2794)
			(stroke
				(width 0.1)
				(type default)
			)
			(layer "F.Fab")
		)
		(fp_line
			(start -0.12065 -0.2794)
			(end 0.12065 -0.2794)
			(stroke
				(width 0.1)
				(type default)
			)
			(layer "F.Fab")
		)
		(fp_line
			(start -0.12065 0.2794)
			(end -0.12065 0.3048)
			(stroke
				(width 0.1)
				(type default)
			)
			(layer "F.Fab")
		)
		(fp_line
			(start -0.12065 0.3048)
			(end -0.67945 0.3048)
			(stroke
				(width 0.1)
				(type default)
			)
			(layer "F.Fab")
		)
		(fp_line
			(start 0.120396 0.2794)
			(end -0.12065 0.2794)
			(stroke
				(width 0.1)
				(type default)
			)
			(layer "F.Fab")
		)
		(fp_line
			(start 0.120396 0.3048)
			(end 0.120396 0.2794)
			(stroke
				(width 0.1)
				(type default)
			)
			(layer "F.Fab")
		)
		(fp_line
			(start 0.12065 -0.3048)
			(end 0.67945 -0.3048)
			(stroke
				(width 0.1)
				(type default)
			)
			(layer "F.Fab")
		)
		(fp_line
			(start 0.12065 -0.2794)
			(end 0.12065 -0.3048)
			(stroke
				(width 0.1)
				(type default)
			)
			(layer "F.Fab")
		)
		(fp_line
			(start 0.67945 -0.3048)
			(end 0.67945 0.3048)
			(stroke
				(width 0.1)
				(type default)
			)
			(layer "F.Fab")
		)
		(fp_line
			(start 0.67945 0.3048)
			(end 0.120396 0.3048)
			(stroke
				(width 0.1)
				(type default)
			)
			(layer "F.Fab")
		)
		(pad "1" smd circle
			(at -0.40005 0)
			(size 0 0)
			(layers "F.Cu" "F.Mask" "F.Paste")
			(net "P3V3_AUX")
		)
		(pad "2" smd circle
			(at 0.40005 0)
			(size 0 0)
			(layers "F.Cu" "F.Mask" "F.Paste")
			(net "GND")
		)
	)
)
